# S9S_MB_2U (Grand Teton) — schematic netlist excerpt (pin names and nets, part order shuffled) for the footprints in the layout excerpt that follows; sources: Cadence DE-HDL packaged netlist, KiCad conversion of 03242023_DA0F0TMBIJ0_F0T_Motherboard_J_brd_V01_OCP.brd

R3503  Q_RES  4.7K 5% CHIP  pkg 0402LF  page 147 : A = P3V3_AUX ; B = GPU_FPGA_EROT_FATALERR

PL7  Q_INDUCTOR4P_14  150NH IND  pkg L_TLM117513Q-151QL_11X7-5XA  page 270
  \1\  = SW_PVCCIN_CPU0_SW8
  \2\  = IND_P0_CPL8
  \3\  = GND
  \4\  = PVCCIN_CPU0

(kicad_pcb
	(version 20260206)
	(generator "pcbnew")
	(generator_version "10.0")
	(general
		(thickness 1.6)
		(legacy_teardrops no)
	)
	(paper "A4")
	(title_block
		(title "03242023_DA0F0TMBIJ0_F0T_Motherboard_J_brd_V01_OCP.brd")
		(comment 1 "Grand Teton / footprints 2684-2685 of 6105")
	)
	(layers
		(0 "F.Cu" signal "TOP")
		(4 "In1.Cu" signal "GND")
		(6 "In2.Cu" signal "IN1")
		(8 "In3.Cu" signal "GND1")
		(10 "In4.Cu" signal "IN2")
		(12 "In5.Cu" signal "GND2")
		(14 "In6.Cu" signal "IN3")
		(16 "In7.Cu" signal "GND3")
		(18 "In8.Cu" signal "VCC")
		(20 "In9.Cu" signal "VCC1")
		(22 "In10.Cu" signal "GND4")
		(24 "In11.Cu" signal "IN4")
		(26 "In12.Cu" signal "GND5")
		(28 "In13.Cu" signal "IN5")
		(30 "In14.Cu" signal "GND6")
		(32 "In15.Cu" signal "IN6")
		(34 "In16.Cu" signal "GND7")
		(2 "B.Cu" signal "BOTTOM")
		(9 "F.Adhes" user "F.Adhesive")
		(11 "B.Adhes" user "B.Adhesive")
		(13 "F.Paste" user "Package Geometry/Pastemask Top")
		(15 "B.Paste" user "Package Geometry/Pastemask Bottom")
		(5 "F.SilkS" user "Ref Des/Silkscreen Top")
		(7 "B.SilkS" user "Ref Des/Silkscreen Bottom")
		(1 "F.Mask" user "Board Geometry/Soldermask Top")
		(3 "B.Mask" user "Board Geometry/Soldermask Bottom")
		(17 "Dwgs.User" user "User.Drawings")
		(19 "Cmts.User" user "User.Comments")
		(21 "Eco1.User" user "User.Eco1")
		(23 "Eco2.User" user "User.Eco2")
		(25 "Edge.Cuts" user "Board Geometry/Outline")
		(27 "Margin" user)
		(31 "F.CrtYd" user "Package Geometry/Place Bound Top")
		(29 "B.CrtYd" user "Package Geometry/Place Bound Bottom")
		(35 "F.Fab" user "Ref Des/Assembly Top")
		(33 "B.Fab" user "Ref Des/Assembly Bottom")
	)
	(footprint ""
		(layer "F.Cu")
		(at 95.095314 -419.722554 90)
		(property "Reference" "R3503"
			(at 0 0 90)
			(layer "F.SilkS")
			(hide yes)
			(effects
				(font
					(size 1.27 1.27)
				)
			)
		)
		(property "Value" ""
			(at 0 0 90)
			(layer "F.Fab")
			(effects
				(font
					(size 1.27 1.27)
				)
			)
		)
		(duplicate_pad_numbers_are_jumpers no)
		(fp_line
			(start 0.7874 -0.4064)
			(end 0.7874 0.4064)
			(stroke
				(width 0.1524)
				(type default)
			)
			(layer "F.SilkS")
		)
		(fp_line
			(start -0.7874 -0.4064)
			(end 0.7874 -0.4064)
			(stroke
				(width 0.1524)
				(type default)
			)
			(layer "F.SilkS")
		)
		(fp_line
			(start 0.7874 0.4064)
			(end -0.7874 0.4064)
			(stroke
				(width 0.1524)
				(type default)
			)
			(layer "F.SilkS")
		)
		(fp_line
			(start -0.7874 0.4064)
			(end -0.7874 -0.4064)
			(stroke
				(width 0.1524)
				(type default)
			)
			(layer "F.SilkS")
		)
		(fp_line
			(start -0.12065 -0.305054)
			(end -0.12065 -0.2794)
			(stroke
				(width 0.1)
				(type default)
			)
			(layer "F.Fab")
		)
		(fp_line
			(start -0.67945 -0.305054)
			(end -0.12065 -0.305054)
			(stroke
				(width 0.1)
				(type default)
			)
			(layer "F.Fab")
		)
		(fp_line
			(start 0.67945 -0.3048)
			(end 0.67945 0.3048)
			(stroke
				(width 0.1)
				(type default)
			)
			(layer "F.Fab")
		)
		(fp_line
			(start 0.12065 -0.3048)
			(end 0.67945 -0.3048)
			(stroke
				(width 0.1)
				(type default)
			)
			(layer "F.Fab")
		)
		(fp_line
			(start 0.12065 -0.2794)
			(end 0.12065 -0.3048)
			(stroke
				(width 0.1)
				(type default)
			)
			(layer "F.Fab")
		)
		(fp_line
			(start -0.12065 -0.2794)
			(end 0.12065 -0.2794)
			(stroke
				(width 0.1)
				(type default)
			)
			(layer "F.Fab")
		)
		(fp_line
			(start 0.120396 0.2794)
			(end -0.12065 0.2794)
			(stroke
				(width 0.1)
				(type default)
			)
			(layer "F.Fab")
		)
		(fp_line
			(start -0.12065 0.2794)
			(end -0.12065 0.3048)
			(stroke
				(width 0.1)
				(type default)
			)
			(layer "F.Fab")
		)
		(fp_line
			(start 0.67945 0.3048)
			(end 0.120396 0.3048)
			(stroke
				(width 0.1)
				(type default)
			)
			(layer "F.Fab")
		)
		(fp_line
			(start 0.120396 0.3048)
			(end 0.120396 0.2794)
			(stroke
				(width 0.1)
				(type default)
			)
			(layer "F.Fab")
		)
		(fp_line
			(start -0.12065 0.3048)
			(end -0.67945 0.3048)
			(stroke
				(width 0.1)
				(type default)
			)
			(layer "F.Fab")
		)
		(fp_line
			(start -0.67945 0.3048)
			(end -0.67945 -0.305054)
			(stroke
				(width 0.1)
				(type default)
			)
			(layer "F.Fab")
		)
		(pad "1" smd circle
			(at -0.40005 0 90)
			(size 0 0)
			(layers "F.Cu" "F.Mask" "F.Paste")
			(net "P3V3_AUX")
		)
		(pad "2" smd circle
			(at 0.40005 0 90)
			(size 0 0)
			(layers "F.Cu" "F.Mask" "F.Paste")
			(net "GPU_FPGA_EROT_FATALERR")
		)
	)
	(footprint ""
		(layer "F.Cu")
		(at 385.858004 -333.55153)
		(property "Reference" "PL7"
			(at 0.123444 6.322314 0)
			(unlocked yes)
			(layer "F.SilkS")
			(effects
				(font
					(size 0.7874 0.5842)
					(thickness 0.1524)
				)
				(justify left)
			)
		)
		(property "Value" ""
			(at 0 0 0)
			(layer "F.Fab")
			(effects
				(font
					(size 1.27 1.27)
				)
			)
		)
		(duplicate_pad_numbers_are_jumpers no)
		(fp_line
			(start -3.750056 -5.500116)
			(end -2.393442 -5.500116)
			(stroke
				(width 0.1524)
				(type default)
			)
			(layer "F.SilkS")
		)
		(fp_line
			(start -3.750056 5.500116)
			(end -3.750056 -5.500116)
			(stroke
				(width 0.1524)
				(type default)
			)
			(layer "F.SilkS")
		)
		(fp_line
			(start -2.393442 5.500116)
			(end -3.750056 5.500116)
			(stroke
				(width 0.1524)
				(type default)
			)
			(layer "F.SilkS")
		)
		(fp_line
			(start 2.393442 5.500116)
			(end 3.750056 5.500116)
			(stroke
				(width 0.1524)
				(type default)
			)
			(layer "F.SilkS")
		)
		(fp_line
			(start 3.750056 -5.500116)
			(end 2.393442 -5.500116)
			(stroke
				(width 0.1524)
				(type default)
			)
			(layer "F.SilkS")
		)
		(fp_line
			(start 3.750056 5.500116)
			(end 3.750056 -5.500116)
			(stroke
				(width 0.1524)
				(type default)
			)
			(layer "F.SilkS")
		)
		(fp_poly
			(pts
				(xy -4.8768 -5.720588) (xy -3.8608 -5.212588) (xy -4.8768 -4.704588)
			)
			(stroke
				(width 0)
				(type default)
			)
			(fill yes)
			(layer "F.SilkS")
		)
		(fp_line
			(start -3.750056 -5.500116)
			(end -3.750056 5.500116)
			(stroke
				(width 0.1)
				(type default)
			)
			(layer "F.Fab")
		)
		(fp_line
			(start -3.750056 5.500116)
			(end 3.750056 5.500116)
			(stroke
				(width 0.1)
				(type default)
			)
			(layer "F.Fab")
		)
		(fp_line
			(start 3.750056 -5.500116)
			(end -3.750056 -5.500116)
			(stroke
				(width 0.1)
				(type default)
			)
			(layer "F.Fab")
		)
		(fp_line
			(start 3.750056 5.500116)
			(end 3.750056 -5.500116)
			(stroke
				(width 0.1)
				(type default)
			)
			(layer "F.Fab")
		)
		(fp_poly
			(pts
				(xy -4.9276 -4.757928) (xy -4.9276 -3.741928) (xy -3.9116 -4.249928)
			)
			(stroke
				(width 0)
				(type default)
			)
			(fill yes)
			(layer "F.Fab")
		)
		(pad "1" smd rect
			(at 0 -4.249928 270)
			(size 2.413 4.5212)
			(layers "F.Cu" "F.Mask" "F.Paste")
			(net "SW_PVCCIN_CPU0_SW8")
		)
		(pad "2" smd rect
			(at 0 -1.175004 270)
			(size 1.3716 4.5212)
			(layers "F.Cu" "F.Mask" "F.Paste")
			(net "IND_P0_CPL8")
		)
		(pad "3" smd rect
			(at 0 1.175004 270)
			(size 1.3716 4.5212)
			(layers "F.Cu" "F.Mask" "F.Paste")
			(net "GND")
		)
		(pad "4" smd rect
			(at 0 4.249928 270)
			(size 2.413 4.5212)
			(layers "F.Cu" "F.Mask" "F.Paste")
			(net "PVCCIN_CPU0")
		)
	)
)
